# S9S_MB_2U (Grand Teton) — schematic netlist excerpt (pin names and nets, part order shuffled) for the footprints in the layout excerpt that follows; sources: Cadence DE-HDL packaged netlist, KiCad conversion of 03242023_DA0F0TMBIJ0_F0T_Motherboard_J_brd_V01_OCP.brd

R55  Q_RES  0 5% CHIP  pkg 0402LF  page 45 : A = SVID_DIO0_CPU1 ; B = SVID_DIO0_CPU1_R
R966  Q_RES  1K 1% CHIP  pkg 0402LF  page 235 : A = P3V3_AUX ; B = SMB_PEHPCPU1_LVC3_SCL

(kicad_pcb
	(version 20260206)
	(generator "pcbnew")
	(generator_version "10.0")
	(general
		(thickness 1.6)
		(legacy_teardrops no)
	)
	(paper "A4")
	(title_block
		(title "03242023_DA0F0TMBIJ0_F0T_Motherboard_J_brd_V01_OCP.brd")
		(comment 1 "Grand Teton / footprints 5630-5631 of 6105")
	)
	(layers
		(0 "F.Cu" signal "TOP")
		(4 "In1.Cu" signal "GND")
		(6 "In2.Cu" signal "IN1")
		(8 "In3.Cu" signal "GND1")
		(10 "In4.Cu" signal "IN2")
		(12 "In5.Cu" signal "GND2")
		(14 "In6.Cu" signal "IN3")
		(16 "In7.Cu" signal "GND3")
		(18 "In8.Cu" signal "VCC")
		(20 "In9.Cu" signal "VCC1")
		(22 "In10.Cu" signal "GND4")
		(24 "In11.Cu" signal "IN4")
		(26 "In12.Cu" signal "GND5")
		(28 "In13.Cu" signal "IN5")
		(30 "In14.Cu" signal "GND6")
		(32 "In15.Cu" signal "IN6")
		(34 "In16.Cu" signal "GND7")
		(2 "B.Cu" signal "BOTTOM")
		(9 "F.Adhes" user "F.Adhesive")
		(11 "B.Adhes" user "B.Adhesive")
		(13 "F.Paste" user "Package Geometry/Pastemask Top")
		(15 "B.Paste" user "Package Geometry/Pastemask Bottom")
		(5 "F.SilkS" user "Ref Des/Silkscreen Top")
		(7 "B.SilkS" user "Ref Des/Silkscreen Bottom")
		(1 "F.Mask" user "Board Geometry/Soldermask Top")
		(3 "B.Mask" user "Board Geometry/Soldermask Bottom")
		(17 "Dwgs.User" user "User.Drawings")
		(19 "Cmts.User" user "User.Comments")
		(21 "Eco1.User" user "User.Eco1")
		(23 "Eco2.User" user "User.Eco2")
		(25 "Edge.Cuts" user "Board Geometry/Outline")
		(27 "Margin" user)
		(31 "F.CrtYd" user "Package Geometry/Place Bound Top")
		(29 "B.CrtYd" user "Package Geometry/Place Bound Bottom")
		(35 "F.Fab" user "Ref Des/Assembly Top")
		(33 "B.Fab" user "Ref Des/Assembly Bottom")
	)
	(footprint ""
		(layer "B.Cu")
		(at 10.558272 -184.625996)
		(property "Reference" "R966"
			(at 0 0 0)
			(layer "B.SilkS")
			(hide yes)
			(effects
				(font
					(size 1.27 1.27)
				)
				(justify mirror)
			)
		)
		(property "Value" ""
			(at 0 0 0)
			(layer "B.Fab")
			(effects
				(font
					(size 1.27 1.27)
				)
				(justify mirror)
			)
		)
		(duplicate_pad_numbers_are_jumpers no)
		(fp_line
			(start -0.7874 -0.4064)
			(end -0.7874 0.4064)
			(stroke
				(width 0.1524)
				(type default)
			)
			(layer "B.SilkS")
		)
		(fp_line
			(start -0.7874 0.4064)
			(end 0.7874 0.4064)
			(stroke
				(width 0.1524)
				(type default)
			)
			(layer "B.SilkS")
		)
		(fp_line
			(start 0.7874 -0.4064)
			(end -0.7874 -0.4064)
			(stroke
				(width 0.1524)
				(type default)
			)
			(layer "B.SilkS")
		)
		(fp_line
			(start 0.7874 0.4064)
			(end 0.7874 -0.4064)
			(stroke
				(width 0.1524)
				(type default)
			)
			(layer "B.SilkS")
		)
		(fp_line
			(start -0.67945 -0.3048)
			(end -0.67945 0.3048)
			(stroke
				(width 0.1)
				(type default)
			)
			(layer "B.Fab")
		)
		(fp_line
			(start -0.67945 0.3048)
			(end -0.120396 0.3048)
			(stroke
				(width 0.1)
				(type default)
			)
			(layer "B.Fab")
		)
		(fp_line
			(start -0.12065 -0.3048)
			(end -0.67945 -0.3048)
			(stroke
				(width 0.1)
				(type default)
			)
			(layer "B.Fab")
		)
		(fp_line
			(start -0.12065 -0.2794)
			(end -0.12065 -0.3048)
			(stroke
				(width 0.1)
				(type default)
			)
			(layer "B.Fab")
		)
		(fp_line
			(start -0.120396 0.2794)
			(end 0.12065 0.2794)
			(stroke
				(width 0.1)
				(type default)
			)
			(layer "B.Fab")
		)
		(fp_line
			(start -0.120396 0.3048)
			(end -0.120396 0.2794)
			(stroke
				(width 0.1)
				(type default)
			)
			(layer "B.Fab")
		)
		(fp_line
			(start 0.12065 -0.305054)
			(end 0.12065 -0.2794)
			(stroke
				(width 0.1)
				(type default)
			)
			(layer "B.Fab")
		)
		(fp_line
			(start 0.12065 -0.2794)
			(end -0.12065 -0.2794)
			(stroke
				(width 0.1)
				(type default)
			)
			(layer "B.Fab")
		)
		(fp_line
			(start 0.12065 0.2794)
			(end 0.12065 0.3048)
			(stroke
				(width 0.1)
				(type default)
			)
			(layer "B.Fab")
		)
		(fp_line
			(start 0.12065 0.3048)
			(end 0.67945 0.3048)
			(stroke
				(width 0.1)
				(type default)
			)
			(layer "B.Fab")
		)
		(fp_line
			(start 0.67945 -0.305054)
			(end 0.12065 -0.305054)
			(stroke
				(width 0.1)
				(type default)
			)
			(layer "B.Fab")
		)
		(fp_line
			(start 0.67945 0.3048)
			(end 0.67945 -0.305054)
			(stroke
				(width 0.1)
				(type default)
			)
			(layer "B.Fab")
		)
		(pad "1" smd circle
			(at 0.40005 0 180)
			(size 0 0)
			(layers "B.Cu" "B.Mask" "B.Paste")
			(net "P3V3_AUX")
		)
		(pad "2" smd circle
			(at -0.40005 0 180)
			(size 0 0)
			(layers "B.Cu" "B.Mask" "B.Paste")
			(net "SMB_PEHPCPU1_LVC3_SCL")
		)
	)
	(footprint ""
		(layer "B.Cu")
		(at 70.369684 -188.458856 90)
		(property "Reference" "R55"
			(at 0 0 90)
			(layer "B.SilkS")
			(hide yes)
			(effects
				(font
					(size 1.27 1.27)
				)
				(justify mirror)
			)
		)
		(property "Value" ""
			(at 0 0 90)
			(layer "B.Fab")
			(effects
				(font
					(size 1.27 1.27)
				)
				(justify mirror)
			)
		)
		(duplicate_pad_numbers_are_jumpers no)
		(fp_line
			(start 0.7874 -0.4064)
			(end -0.7874 -0.4064)
			(stroke
				(width 0.1524)
				(type default)
			)
			(layer "B.SilkS")
		)
		(fp_line
			(start -0.7874 -0.4064)
			(end -0.7874 0.4064)
			(stroke
				(width 0.1524)
				(type default)
			)
			(layer "B.SilkS")
		)
		(fp_line
			(start 0.7874 0.4064)
			(end 0.7874 -0.4064)
			(stroke
				(width 0.1524)
				(type default)
			)
			(layer "B.SilkS")
		)
		(fp_line
			(start -0.7874 0.4064)
			(end 0.7874 0.4064)
			(stroke
				(width 0.1524)
				(type default)
			)
			(layer "B.SilkS")
		)
		(fp_line
			(start 0.67945 -0.305054)
			(end 0.12065 -0.305054)
			(stroke
				(width 0.1)
				(type default)
			)
			(layer "B.Fab")
		)
		(fp_line
			(start 0.12065 -0.305054)
			(end 0.12065 -0.2794)
			(stroke
				(width 0.1)
				(type default)
			)
			(layer "B.Fab")
		)
		(fp_line
			(start -0.12065 -0.3048)
			(end -0.67945 -0.3048)
			(stroke
				(width 0.1)
				(type default)
			)
			(layer "B.Fab")
		)
		(fp_line
			(start -0.67945 -0.3048)
			(end -0.67945 0.3048)
			(stroke
				(width 0.1)
				(type default)
			)
			(layer "B.Fab")
		)
		(fp_line
			(start 0.12065 -0.2794)
			(end -0.12065 -0.2794)
			(stroke
				(width 0.1)
				(type default)
			)
			(layer "B.Fab")
		)
		(fp_line
			(start -0.12065 -0.2794)
			(end -0.12065 -0.3048)
			(stroke
				(width 0.1)
				(type default)
			)
			(layer "B.Fab")
		)
		(fp_line
			(start 0.12065 0.2794)
			(end 0.12065 0.3048)
			(stroke
				(width 0.1)
				(type default)
			)
			(layer "B.Fab")
		)
		(fp_line
			(start -0.120396 0.2794)
			(end 0.12065 0.2794)
			(stroke
				(width 0.1)
				(type default)
			)
			(layer "B.Fab")
		)
		(fp_line
			(start 0.67945 0.3048)
			(end 0.67945 -0.305054)
			(stroke
				(width 0.1)
				(type default)
			)
			(layer "B.Fab")
		)
		(fp_line
			(start 0.12065 0.3048)
			(end 0.67945 0.3048)
			(stroke
				(width 0.1)
				(type default)
			)
			(layer "B.Fab")
		)
		(fp_line
			(start -0.120396 0.3048)
			(end -0.120396 0.2794)
			(stroke
				(width 0.1)
				(type default)
			)
			(layer "B.Fab")
		)
		(fp_line
			(start -0.67945 0.3048)
			(end -0.120396 0.3048)
			(stroke
				(width 0.1)
				(type default)
			)
			(layer "B.Fab")
		)
		(pad "1" smd circle
			(at 0.40005 0 270)
			(size 0 0)
			(layers "B.Cu" "B.Mask" "B.Paste")
			(net "SVID_DIO0_CPU1")
		)
		(pad "2" smd circle
			(at -0.40005 0 270)
			(size 0 0)
			(layers "B.Cu" "B.Mask" "B.Paste")
			(net "SVID_DIO0_CPU1_R")
		)
	)
)
